FILE_TYPE = CONNECTIVITY;
{Allegro Design Entry HDL 17.2-2016 S081 (4005846) 1/11/2022}
"PAGE_NUMBER" = 90;
0"NC";
1"P3V3_AUX\g";
2"P12V_S3_AUX_CPU0_NVDIMM\g";
3"P12V_S3_AUX_CPU0_NVDIMM\g";
4"P3V3_AUX\g";
5"GND\g";
6"GND\g";
7"GND\g";
8"GND\g";
9"GND\g";
10"M_E_CPU0_SA_DQ<31:0>";
11"M_E_CPU0_SA_CB<7:0>";
12"M_E_CPU0_SB_CB<7:0>";
13"M_E_CPU0_SA_CA<6:0>";
14"M_E_CPU0_SB_CA<6:0>";
15"M_E_CPU0_SB_DQ<31:0>";
16"M_E_CPU0_SB_DQS_DP<9:0>";
17"M_E_CPU0_SA_DQS_DP<9:0>";
18"M_E_CPU0_SB_DQS_DN<9:0>";
19"M_E_CPU0_SA_DQS_DN<9:0>";
20"TP_CHE_CPU0_DIMM1_FRU_0";
21"TP_CHE_CPU0_DIMM1_FRU_3";
22"TP_CHE_CPU0_DIMM1_FRU_4";
23"TP_CHE_CPU0_DIMM1_FRU_5";
24"TP_CHE_CPU0_DIMM1_FRU_6";
25"PWRGD_CHE_CPU0_DIMM1";
26"I3C_SPD_DDREFGH_CPU0_LVC1_SCL";
27"I3C_SPD_DDREFGH_CPU0_LVC1_SCL_R1";
28"PD_CHE_CPU0_DIMM1_SAA";
29"M_E_CPU0_ALERT_N";
30"TP_CHE_CPU0_DIMM1_FRU_2";
31"TP_CHE_CPU0_DIMM1_FRU_1";
32"I3C_SPD_DDREFGH_CPU0_LVC1_SDA";
33"RST_M_EF_CPU0_FPGA_N";
34"M_E_CPU0_CLK_DN<0>";
35"M_E_CPU0_SA_CS_N<0>";
36"M_E_CPU0_SB_CS_N<1>";
37"M_E_CPU0_SB_CS_N<0>";
38"M_E_CPU0_SB_DQ<29>";
39"M_E_CPU0_SA_DQS_DN<9>";
40"M_E_CPU0_SA_DQS_DN<8>";
41"M_E_CPU0_SA_DQS_DN<7>";
42"M_E_CPU0_SA_DQS_DN<6>";
43"M_E_CPU0_SA_DQS_DN<5>";
44"M_E_CPU0_SA_DQS_DN<4>";
45"M_E_CPU0_SA_DQS_DN<3>";
46"M_E_CPU0_SA_DQS_DN<2>";
47"M_E_CPU0_SA_DQS_DN<1>";
48"M_E_CPU0_SA_DQS_DN<0>";
49"M_E_CPU0_SB_DQS_DN<9>";
50"M_E_CPU0_SB_DQS_DN<8>";
51"M_E_CPU0_SB_DQS_DN<7>";
52"M_E_CPU0_SB_DQS_DN<6>";
53"M_E_CPU0_SB_DQS_DN<5>";
54"M_E_CPU0_SB_DQS_DN<4>";
55"M_E_CPU0_SB_DQS_DN<3>";
56"M_E_CPU0_SB_DQS_DN<2>";
57"M_E_CPU0_SB_DQS_DN<1>";
58"M_E_CPU0_SB_DQS_DN<0>";
59"M_E_CPU0_SA_DQS_DP<9>";
60"M_E_CPU0_SA_DQS_DP<8>";
61"M_E_CPU0_SA_DQS_DP<7>";
62"M_E_CPU0_SA_DQS_DP<6>";
63"M_E_CPU0_SA_DQS_DP<5>";
64"M_E_CPU0_SA_DQS_DP<4>";
65"M_E_CPU0_SA_DQS_DP<3>";
66"M_E_CPU0_SA_DQS_DP<2>";
67"M_E_CPU0_SA_DQS_DP<1>";
68"M_E_CPU0_SA_DQS_DP<0>";
69"M_E_CPU0_SB_DQS_DP<9>";
70"M_E_CPU0_SB_DQS_DP<8>";
71"M_E_CPU0_SB_DQS_DP<7>";
72"M_E_CPU0_SB_DQS_DP<6>";
73"M_E_CPU0_SB_DQS_DP<5>";
74"M_E_CPU0_SB_DQS_DP<4>";
75"M_E_CPU0_SB_DQS_DP<3>";
76"M_E_CPU0_SB_DQS_DP<2>";
77"M_E_CPU0_SB_DQS_DP<1>";
78"M_E_CPU0_SB_DQS_DP<0>";
79"M_E_CPU0_SA_DQ<24>";
80"M_E_CPU0_SB_CA<2>";
81"M_E_CPU0_SB_CA<1>";
82"M_E_CPU0_SA_PAR";
83"M_E_CPU0_SA_DQ<21>";
84"M_E_CPU0_SA_DQ<20>";
85"M_E_CPU0_SA_DQ<10>";
86"M_E_CPU0_SA_DQ<4>";
87"M_E_CPU0_SA_DQ<5>";
88"M_E_CPU0_SA_DQ<9>";
89"M_E_CPU0_SA_DQ<8>";
90"M_E_CPU0_SA_DQ<6>";
91"M_E_CPU0_SB_DQ<30>";
92"M_E_CPU0_SB_DQ<28>";
93"M_E_CPU0_SA_CB<0>";
94"M_E_CPU0_SB_CB<6>";
95"M_E_CPU0_SB_CB<5>";
96"M_E_CPU0_SB_DQ<20>";
97"M_E_CPU0_SB_DQ<15>";
98"M_E_CPU0_SB_PAR";
99"M_E_CPU0_SB_RSP<0>";
100"M_E_CPU0_SA_RSP<0>";
101"M_E_CPU0_SB_DQ<0>";
102"M_E_CPU0_SB_DQ<1>";
103"M_E_CPU0_SB_DQ<2>";
104"M_E_CPU0_SB_DQ<3>";
105"M_E_CPU0_SB_DQ<4>";
106"M_E_CPU0_SB_DQ<5>";
107"M_E_CPU0_SB_DQ<6>";
108"M_E_CPU0_SB_DQ<7>";
109"M_E_CPU0_SB_DQ<8>";
110"M_E_CPU0_SB_DQ<9>";
111"M_E_CPU0_SB_DQ<10>";
112"M_E_CPU0_SB_DQ<11>";
113"M_E_CPU0_SB_DQ<12>";
114"M_E_CPU0_SB_DQ<13>";
115"M_E_CPU0_SB_DQ<14>";
116"M_E_CPU0_SB_DQ<16>";
117"M_E_CPU0_SB_DQ<17>";
118"M_E_CPU0_SB_DQ<18>";
119"M_E_CPU0_SB_DQ<19>";
120"M_E_CPU0_SB_DQ<21>";
121"M_E_CPU0_SB_DQ<22>";
122"M_E_CPU0_SB_DQ<23>";
123"M_E_CPU0_SB_DQ<24>";
124"M_E_CPU0_SB_DQ<25>";
125"M_E_CPU0_SB_DQ<26>";
126"M_E_CPU0_SB_DQ<27>";
127"M_E_CPU0_SB_DQ<31>";
128"M_E_CPU0_SA_DQ<0>";
129"M_E_CPU0_SA_DQ<1>";
130"M_E_CPU0_SA_DQ<2>";
131"M_E_CPU0_SA_DQ<3>";
132"M_E_CPU0_SA_DQ<7>";
133"M_E_CPU0_SA_DQ<11>";
134"M_E_CPU0_SA_DQ<12>";
135"M_E_CPU0_SA_DQ<13>";
136"M_E_CPU0_SA_DQ<14>";
137"M_E_CPU0_SA_DQ<15>";
138"M_E_CPU0_SA_DQ<16>";
139"M_E_CPU0_SA_DQ<17>";
140"M_E_CPU0_SA_DQ<18>";
141"M_E_CPU0_SA_DQ<19>";
142"M_E_CPU0_SA_DQ<22>";
143"M_E_CPU0_SA_DQ<23>";
144"M_E_CPU0_SA_DQ<25>";
145"M_E_CPU0_SA_DQ<26>";
146"M_E_CPU0_SA_DQ<27>";
147"M_E_CPU0_SA_DQ<28>";
148"M_E_CPU0_SA_DQ<29>";
149"M_E_CPU0_SA_DQ<30>";
150"M_E_CPU0_SA_CS_N<1>";
151"M_E_CPU0_CLK_DP<0>";
152"M_E_CPU0_SB_CB<0>";
153"M_E_CPU0_SB_CB<1>";
154"M_E_CPU0_SB_CB<2>";
155"M_E_CPU0_SB_CB<3>";
156"M_E_CPU0_SB_CB<4>";
157"M_E_CPU0_SA_CB<2>";
158"M_E_CPU0_SA_CB<3>";
159"M_E_CPU0_SA_CB<5>";
160"M_E_CPU0_SA_CB<6>";
161"M_E_CPU0_SB_CA<6>";
162"M_E_CPU0_SA_CA<6>";
163"M_E_CPU0_SB_CA<5>";
164"M_E_CPU0_SA_CA<5>";
165"M_E_CPU0_SB_CA<4>";
166"M_E_CPU0_SA_CA<4>";
167"M_E_CPU0_SB_CA<3>";
168"M_E_CPU0_SA_CA<3>";
169"M_E_CPU0_SA_CA<2>";
170"M_E_CPU0_SA_CA<1>";
171"M_E_CPU0_SB_CA<0>";
172"M_E_CPU0_SA_CA<0>";
173"M_E_CPU0_SB_CB<7>";
174"M_E_CPU0_SA_CB<1>";
175"M_E_CPU0_SA_CB<4>";
176"M_E_CPU0_SA_CB<7>";
177"M_E_CPU0_SA_DQ<31>";
178"PD_CHE_CPU0_DIMM1_SAA";
%"UNIVERSAL_GND"
"1","(-1425,-350)","0","logical_power","I1";
;
CDS_LIB"logical_power"
HDL_POWER"GND";
"A"9;
%"TAP"
"1","(0,3375)","0","standard","I100";
;
CDS_LIB"standard"
BODY_TYPE"PLUMBING"
HDL_TAP"TRUE";
"B \NAC \NWC"10;
"S \NAC"
BN"18"140;
%"TAP"
"1","(0,3325)","0","standard","I101";
;
CDS_LIB"standard"
BODY_TYPE"PLUMBING"
HDL_TAP"TRUE";
"B \NAC \NWC"10;
"S \NAC"
BN"17"139;
%"TAP"
"1","(0,3475)","0","standard","I102";
;
CDS_LIB"standard"
BODY_TYPE"PLUMBING"
HDL_TAP"TRUE";
"B \NAC \NWC"10;
"S \NAC"
BN"20"84;
%"TAP"
"1","(0,3525)","0","standard","I103";
;
CDS_LIB"standard"
BODY_TYPE"PLUMBING"
HDL_TAP"TRUE";
"B \NAC \NWC"10;
"S \NAC"
BN"21"83;
%"TAP"
"1","(0,3575)","0","standard","I104";
;
CDS_LIB"standard"
BODY_TYPE"PLUMBING"
HDL_TAP"TRUE";
"B \NAC \NWC"10;
"S \NAC"
BN"22"142;
%"TAP"
"1","(0,3625)","0","standard","I105";
;
CDS_LIB"standard"
BODY_TYPE"PLUMBING"
HDL_TAP"TRUE";
"B \NAC \NWC"10;
"S \NAC"
BN"23"143;
%"TAP"
"1","(0,3675)","0","standard","I106";
;
CDS_LIB"standard"
BODY_TYPE"PLUMBING"
HDL_TAP"TRUE";
"B \NAC \NWC"10;
"S \NAC"
BN"24"79;
%"TAP"
"1","(0,3725)","0","standard","I107";
;
CDS_LIB"standard"
BODY_TYPE"PLUMBING"
HDL_TAP"TRUE";
"B \NAC \NWC"10;
"S \NAC"
BN"25"144;
%"TAP"
"1","(0,3775)","0","standard","I108";
;
CDS_LIB"standard"
BODY_TYPE"PLUMBING"
HDL_TAP"TRUE";
"B \NAC \NWC"10;
"S \NAC"
BN"26"145;
%"Q_RES"
"2","(-1425,-125)","0","pure_quanta","I11";
;
PART_NUMBER"CS31002FB08"
TOLERANCE"1%"
PACK_TYPE"0402LF"
VALUE"10K"
MATERIAL"CHIP"
WATTAGE"1/16W"
$LOCATION"R34"
CDS_LIB"pure_quanta"
CDS_LOCATION"R34"
$SEC"1"
CDS_SEC"1";
"A"
$PN"1"178;
"B"
$PN"2"9;
%"TAP"
"1","(-1650,3825)","2","standard","I110";
;
CDS_LIB"standard"
BODY_TYPE"PLUMBING"
HDL_TAP"TRUE";
"B \NAC \NWC"13;
"S \NAC"
BN"2"169;
%"TAP"
"1","(-1650,3875)","2","standard","I111";
;
CDS_LIB"standard"
BODY_TYPE"PLUMBING"
HDL_TAP"TRUE";
"B \NAC \NWC"13;
"S \NAC"
BN"3"168;
%"TAP"
"1","(-1650,3925)","2","standard","I112";
;
CDS_LIB"standard"
BODY_TYPE"PLUMBING"
HDL_TAP"TRUE";
"B \NAC \NWC"13;
"S \NAC"
BN"4"166;
%"TAP"
"1","(-1650,4025)","2","standard","I113";
;
CDS_LIB"standard"
BODY_TYPE"PLUMBING"
HDL_TAP"TRUE";
"B \NAC \NWC"13;
"S \NAC"
BN"6"162;
%"TAP"
"1","(-1650,3975)","2","standard","I114";
;
CDS_LIB"standard"
BODY_TYPE"PLUMBING"
HDL_TAP"TRUE";
"B \NAC \NWC"13;
"S \NAC"
BN"5"164;
%"TAP"
"1","(0,3925)","0","standard","I115";
;
CDS_LIB"standard"
BODY_TYPE"PLUMBING"
HDL_TAP"TRUE";
"B \NAC \NWC"10;
"S \NAC"
BN"29"148;
%"TAP"
"1","(0,3825)","0","standard","I116";
;
CDS_LIB"standard"
BODY_TYPE"PLUMBING"
HDL_TAP"TRUE";
"B \NAC \NWC"10;
"S \NAC"
BN"27"146;
%"TAP"
"1","(0,3875)","0","standard","I117";
;
CDS_LIB"standard"
BODY_TYPE"PLUMBING"
HDL_TAP"TRUE";
"B \NAC \NWC"10;
"S \NAC"
BN"28"147;
%"TAP"
"1","(0,3975)","0","standard","I118";
;
CDS_LIB"standard"
BODY_TYPE"PLUMBING"
HDL_TAP"TRUE";
"B \NAC \NWC"10;
"S \NAC"
BN"30"149;
%"TAP"
"1","(0,4025)","0","standard","I119";
;
CDS_LIB"standard"
BODY_TYPE"PLUMBING"
HDL_TAP"TRUE";
"B \NAC \NWC"10;
"S \NAC"
BN"31"177;
%"SCONN288_ADR50017P130CC"
"1","(-825,2300)","0","pure_quanta","I12";
;
PART_NUMBER"DFHST8FS461"
MATERIAL"IO"
VALUE"SCONN288_ADR50017-P130CC"
PART_TYPE"SMLF"
$LOCATION"J9"
NEEDS_NO_SIZE"TRUE"
CDS_LMAN_SYM_OUTLINE"-450,1875,450,-1875"
CDS_LIB"pure_quanta"
CDS_LOCATION"J9"
$SEC"1"
CDS_SEC"1";
"DQ31_A"
$PN"194"177;
"CB7_A"
$PN"205"176;
"CB4_A"
$PN"58"175;
"CB1_A"
$PN"53"174;
"CB7_B"
$PN"236"173;
"ALERT_N \B"
$PN"62"29;
"CA0_A"
$PN"66"172;
"CA0_B"
$PN"76"171;
"CA1_A"
$PN"211"170;
"CA1_B"
$PN"221"81;
"CA2_A"
$PN"68"169;
"CA2_B"
$PN"78"80;
"CA3_A"
$PN"213"168;
"CA3_B"
$PN"223"167;
"CA4_A"
$PN"70"166;
"CA4_B"
$PN"80"165;
"CA5_A"
$PN"215"164;
"CA5_B"
$PN"225"163;
"CA6_A"
$PN"72"162;
"CA6_B"
$PN"82"161;
"CB6_A"
$PN"203"160;
"CB5_A"
$PN"60"159;
"CB3_A"
$PN"198"158;
"CB2_A"
$PN"196"157;
"CB0_A"
$PN"51"93;
"CB6_B"
$PN"234"94;
"CB5_B"
$PN"91"95;
"CB4_B"
$PN"89"156;
"CB3_B"
$PN"243"155;
"CB2_B"
$PN"241"154;
"CB1_B"
$PN"98"153;
"CB0_B"
$PN"96"152;
"CK_C \B"
$PN"218"34;
"CK_T"
$PN"217"151;
"CS0_A_N"
$PN"64"35;
"CS0_B_N"
$PN"84"37;
"CS1_A_N"
$PN"209"150;
"CS1_B_N"
$PN"229"36;
"DQ30_A"
$PN"192"149;
"DQ29_A"
$PN"49"148;
"DQ28_A"
$PN"47"147;
"DQ27_A"
$PN"187"146;
"DQ26_A"
$PN"185"145;
"DQ25_A"
$PN"42"144;
"DQ24_A"
$PN"40"79;
"DQ23_A"
$PN"183"143;
"DQ22_A"
$PN"181"142;
"DQ21_A"
$PN"38"83;
"DQ20_A"
$PN"36"84;
"DQ19_A"
$PN"176"141;
"DQ18_A"
$PN"174"140;
"DQ17_A"
$PN"31"139;
"DQ16_A"
$PN"29"138;
"DQ15_A"
$PN"172"137;
"DQ14_A"
$PN"170"136;
"DQ13_A"
$PN"27"135;
"DQ12_A"
$PN"25"134;
"DQ11_A"
$PN"165"133;
"DQ10_A"
$PN"163"85;
"DQ9_A"
$PN"20"88;
"DQ8_A"
$PN"18"89;
"DQ7_A"
$PN"161"132;
"DQ6_A"
$PN"159"90;
"DQ5_A"
$PN"16"87;
"DQ4_A"
$PN"14"86;
"DQ3_A"
$PN"154"131;
"DQ2_A"
$PN"152"130;
"DQ1_A"
$PN"9"129;
"DQ0_A"
$PN"7"128;
"DQ31_B"
$PN"287"127;
"DQ30_B"
$PN"285"91;
"DQ29_B"
$PN"142"38;
"DQ28_B"
$PN"140"92;
"DQ27_B"
$PN"280"126;
"DQ26_B"
$PN"278"125;
"DQ25_B"
$PN"135"124;
"DQ24_B"
$PN"133"123;
"DQ23_B"
$PN"276"122;
"DQ22_B"
$PN"274"121;
"DQ21_B"
$PN"131"120;
"DQ20_B"
$PN"129"96;
"DQ19_B"
$PN"269"119;
"DQ18_B"
$PN"267"118;
"DQ17_B"
$PN"124"117;
"DQ16_B"
$PN"122"116;
"DQ15_B"
$PN"265"97;
"DQ14_B"
$PN"263"115;
"DQ13_B"
$PN"120"114;
"DQ12_B"
$PN"118"113;
"DQ11_B"
$PN"258"112;
"DQ10_B"
$PN"256"111;
"DQ9_B"
$PN"113"110;
"DQ8_B"
$PN"111"109;
"DQ7_B"
$PN"254"108;
"DQ6_B"
$PN"252"107;
"DQ5_B"
$PN"109"106;
"DQ4_B"
$PN"107"105;
"DQ3_B"
$PN"247"104;
"DQ2_B"
$PN"245"103;
"DQ1_B"
$PN"102"102;
"DQ0_B"
$PN"100"101;
"HSA"
$PN"148"28;
"HSCL"
$PN"4"27;
"HSDA"
$PN"5"32;
"LBD||RSP_A_N"
$PN"86"100;
"LBS||RSP_B_N"
$PN"87"99;
"PAR_A"
$PN"74"82;
"PAR_B"
$PN"227"98;
"PWR_GOOD||FAIL_N"
$PN"147"25;
"RESET_N \B"
$PN"207"33;
"RFU6"
$PN"232"24;
"RFU5"
$PN"231"23;
"RFU4"
$PN"220"22;
"RFU3"
$PN"150"21;
"RFU2"
$PN"149"30;
"RFU1"
$PN"144"31;
"RFU0"
$PN"2"20;
"VIN_MGMT"
$PN"3"1;
%"VCC_CORE"
"1","(1725,475)","0","logical_power","I120";
;
HDL_POWER"P3V3_AUX"
CDS_LIB"logical_power";
"A"4;
%"UNIVERSAL_GND"
"1","(1725,-225)","0","logical_power","I121";
;
CDS_LIB"logical_power"
HDL_POWER"GND";
"A"8;
%"Q_CAP"
"1","(1725,150)","0","pure_quanta","I122";
;
PART_NUMBER"CH5221MEB00"
PACK_TYPE"C0402"
TOLERANCE"20%"
VALUE"2.2UF"
MATERIAL"X6S"
VOLTAGE"6.3V"
$LOCATION"C26"
CDS_LIB"pure_quanta"
CDS_LOCATION"C26"
$SEC"1"
CDS_SEC"1";
"B"
$PN"2"8;
"A"
$PN"1"4;
%"Q_CAP"
"1","(2725,150)","0","pure_quanta","I123";
;
PART_NUMBER"CH6103KEA00"
PACK_TYPE"C0805"
VOLTAGE"16V"
VALUE"10UF"
TOLERANCE"10%"
MATERIAL"X6S"
$LOCATION"C27"
CDS_LIB"pure_quanta"
CDS_LOCATION"C27"
$SEC"1"
CDS_SEC"1";
"B"
$PN"2"7;
"A"
$PN"1"3;
%"VCC_CORE"
"1","(2725,475)","0","logical_power","I124";
;
HDL_POWER"P12V_S3_AUX_CPU0_NVDIMM"
CDS_LIB"logical_power";
"A"3;
%"TAP"
"1","(2750,2075)","0","standard","I127";
;
CDS_LIB"standard"
BODY_TYPE"PLUMBING"
HDL_TAP"TRUE";
"B \NAC \NWC"16;
"S \NAC"
BN"0"78;
%"TAP"
"1","(2750,2275)","0","standard","I128";
;
CDS_LIB"standard"
BODY_TYPE"PLUMBING"
HDL_TAP"TRUE";
"B \NAC \NWC"16;
"S \NAC"
BN"2"76;
%"TAP"
"1","(2750,2175)","0","standard","I129";
;
CDS_LIB"standard"
BODY_TYPE"PLUMBING"
HDL_TAP"TRUE";
"B \NAC \NWC"16;
"S \NAC"
BN"1"77;
%"TAP"
"1","(2750,2375)","0","standard","I130";
;
CDS_LIB"standard"
BODY_TYPE"PLUMBING"
HDL_TAP"TRUE";
"B \NAC \NWC"16;
"S \NAC"
BN"3"75;
%"TAP"
"1","(2750,2475)","0","standard","I131";
;
CDS_LIB"standard"
BODY_TYPE"PLUMBING"
HDL_TAP"TRUE";
"B \NAC \NWC"16;
"S \NAC"
BN"4"74;
%"TAP"
"1","(2750,2575)","0","standard","I132";
;
CDS_LIB"standard"
BODY_TYPE"PLUMBING"
HDL_TAP"TRUE";
"B \NAC \NWC"16;
"S \NAC"
BN"5"73;
%"TAP"
"1","(2750,2775)","0","standard","I133";
;
CDS_LIB"standard"
BODY_TYPE"PLUMBING"
HDL_TAP"TRUE";
"B \NAC \NWC"16;
"S \NAC"
BN"7"71;
%"TAP"
"1","(2750,2675)","0","standard","I134";
;
CDS_LIB"standard"
BODY_TYPE"PLUMBING"
HDL_TAP"TRUE";
"B \NAC \NWC"16;
"S \NAC"
BN"6"72;
%"TAP"
"1","(2750,2875)","0","standard","I135";
;
CDS_LIB"standard"
BODY_TYPE"PLUMBING"
HDL_TAP"TRUE";
"B \NAC \NWC"16;
"S \NAC"
BN"8"70;
%"TAP"
"1","(2750,2975)","0","standard","I136";
;
CDS_LIB"standard"
BODY_TYPE"PLUMBING"
HDL_TAP"TRUE";
"B \NAC \NWC"16;
"S \NAC"
BN"9"69;
%"TAP"
"1","(2750,3125)","0","standard","I137";
;
CDS_LIB"standard"
BODY_TYPE"PLUMBING"
HDL_TAP"TRUE";
"B \NAC \NWC"17;
"S \NAC"
BN"0"68;
%"TAP"
"1","(2750,3225)","0","standard","I138";
;
CDS_LIB"standard"
BODY_TYPE"PLUMBING"
HDL_TAP"TRUE";
"B \NAC \NWC"17;
"S \NAC"
BN"1"67;
%"TAP"
"1","(2750,3325)","0","standard","I139";
;
CDS_LIB"standard"
BODY_TYPE"PLUMBING"
HDL_TAP"TRUE";
"B \NAC \NWC"17;
"S \NAC"
BN"2"66;
%"VCC_CORE"
"1","(-2475,1900)","0","logical_power","I14";
;
HDL_POWER"P3V3_AUX"
CDS_LIB"logical_power";
"A"1;
%"TAP"
"1","(2750,3425)","0","standard","I140";
;
CDS_LIB"standard"
BODY_TYPE"PLUMBING"
HDL_TAP"TRUE";
"B \NAC \NWC"17;
"S \NAC"
BN"3"65;
%"TAP"
"1","(2750,3525)","0","standard","I141";
;
CDS_LIB"standard"
BODY_TYPE"PLUMBING"
HDL_TAP"TRUE";
"B \NAC \NWC"17;
"S \NAC"
BN"4"64;
%"TAP"
"1","(2750,3625)","0","standard","I142";
;
CDS_LIB"standard"
BODY_TYPE"PLUMBING"
HDL_TAP"TRUE";
"B \NAC \NWC"17;
"S \NAC"
BN"5"63;
%"TAP"
"1","(2750,3725)","0","standard","I143";
;
CDS_LIB"standard"
BODY_TYPE"PLUMBING"
HDL_TAP"TRUE";
"B \NAC \NWC"17;
"S \NAC"
BN"6"62;
%"UNIVERSAL_GND"
"1","(3350,-225)","0","logical_power","I144";
;
CDS_LIB"logical_power"
HDL_POWER"GND";
"A"7;
%"Q_CAP"
"1","(3350,150)","0","pure_quanta","I145";
;
PART_NUMBER"CH6103KEA00"
PACK_TYPE"C0805"
TOLERANCE"10%"
VOLTAGE"16V"
VALUE"10UF"
MATERIAL"X6S"
$LOCATION"C28"
CDS_LIB"pure_quanta"
CDS_LOCATION"C28"
$SEC"1"
CDS_SEC"1";
"B"
$PN"2"7;
"A"
$PN"1"3;
%"UNIVERSAL_GND"
"1","(4425,325)","0","logical_power","I146";
;
CDS_LIB"logical_power"
HDL_POWER"GND";
"A"6;
%"SCONN288_ADR50017P130CC"
"3","(5275,2400)","0","pure_quanta","I147";
;
PART_NUMBER"DFHST8FS461"
MATERIAL"IO"
PART_TYPE"SMLF"
VALUE"SCONN288_ADR50017-P130CC"
$LOCATION"J9"
NEEDS_NO_SIZE"TRUE"
CDS_LMAN_SYM_OUTLINE"-450,1775,450,-1775"
CDS_LIB"pure_quanta"
CDS_LOCATION"J9"
$SEC"3"
CDS_SEC"3";
"G3"
$PN"G3"5;
"G2"
$PN"G2"5;
"G1"
$PN"G1"5;
"VSS62"
$PN"141"5;
"VSS61"
$PN"139"5;
"VSS60"
$PN"136"5;
"VSS58"
$PN"132"5;
"VSS104"
$PN"240"6;
"VSS102"
$PN"235"6;
"VSS100"
$PN"230"6;
"VIN_BULK2"
$PN"146"2;
"VIN_BULK1"
$PN"145"2;
"VIN_BULK0"
$PN"1"2;
"VSS126"
$PN"288"6;
"VSS125"
$PN"286"6;
"VSS124"
$PN"284"6;
"VSS123"
$PN"281"6;
"VSS122"
$PN"279"6;
"VSS121"
$PN"277"6;
"VSS120"
$PN"275"6;
"VSS119"
$PN"273"6;
"VSS118"
$PN"270"6;
"VSS117"
$PN"268"6;
"VSS116"
$PN"266"6;
"VSS115"
$PN"264"6;
"VSS114"
$PN"262"6;
"VSS113"
$PN"259"6;
"VSS112"
$PN"257"6;
"VSS111"
$PN"255"6;
"VSS110"
$PN"253"6;
"VSS109"
$PN"251"6;
"VSS108"
$PN"248"6;
"VSS107"
$PN"246"6;
"VSS106"
$PN"244"6;
"VSS105"
$PN"242"6;
"VSS103"
$PN"237"6;
"VSS101"
$PN"233"6;
"VSS99"
$PN"228"6;
"VSS98"
$PN"226"6;
"VSS97"
$PN"224"6;
"VSS96"
$PN"222"6;
"VSS95"
$PN"219"6;
"VSS94"
$PN"216"6;
"VSS93"
$PN"214"6;
"VSS92"
$PN"212"6;
"VSS91"
$PN"210"6;
"VSS90"
$PN"208"6;
"VSS89"
$PN"206"6;
"VSS88"
$PN"204"6;
"VSS87"
$PN"202"6;
"VSS86"
$PN"199"6;
"VSS85"
$PN"197"6;
"VSS84"
$PN"195"6;
"VSS83"
$PN"193"6;
"VSS82"
$PN"191"6;
"VSS81"
$PN"188"6;
"VSS80"
$PN"186"6;
"VSS79"
$PN"184"6;
"VSS78"
$PN"182"6;
"VSS77"
$PN"180"6;
"VSS76"
$PN"177"6;
"VSS75"
$PN"175"6;
"VSS74"
$PN"173"6;
"VSS73"
$PN"171"6;
"VSS72"
$PN"169"6;
"VSS71"
$PN"166"6;
"VSS70"
$PN"164"6;
"VSS69"
$PN"162"6;
"VSS68"
$PN"160"6;
"VSS67"
$PN"158"6;
"VSS66"
$PN"155"6;
"VSS65"
$PN"153"6;
"VSS64"
$PN"151"6;
"VSS63"
$PN"143"5;
"VSS59"
$PN"134"5;
"VSS57"
$PN"130"5;
"VSS56"
$PN"128"5;
"VSS55"
$PN"125"5;
"VSS54"
$PN"123"5;
"VSS53"
$PN"121"5;
"VSS52"
$PN"119"5;
"VSS51"
$PN"117"5;
"VSS50"
$PN"114"5;
"VSS49"
$PN"112"5;
"VSS48"
$PN"110"5;
"VSS47"
$PN"108"5;
"VSS46"
$PN"106"5;
"VSS45"
$PN"103"5;
"VSS44"
$PN"101"5;
"VSS43"
$PN"99"5;
"VSS42"
$PN"97"5;
"VSS41"
$PN"95"5;
"VSS40"
$PN"92"5;
"VSS39"
$PN"90"5;
"VSS38"
$PN"88"5;
"VSS37"
$PN"85"5;
"VSS36"
$PN"83"5;
"VSS35"
$PN"81"5;
"VSS34"
$PN"79"5;
"VSS33"
$PN"77"5;
"VSS32"
$PN"75"5;
"VSS31"
$PN"73"5;
"VSS30"
$PN"71"5;
"VSS29"
$PN"69"5;
"VSS28"
$PN"67"5;
"VSS27"
$PN"65"5;
"VSS26"
$PN"63"5;
"VSS25"
$PN"61"5;
"VSS24"
$PN"59"5;
"VSS23"
$PN"57"5;
"VSS22"
$PN"54"5;
"VSS21"
$PN"52"5;
"VSS20"
$PN"50"5;
"VSS19"
$PN"48"5;
"VSS18"
$PN"46"5;
"VSS17"
$PN"43"5;
"VSS16"
$PN"41"5;
"VSS15"
$PN"39"5;
"VSS14"
$PN"37"5;
"VSS13"
$PN"35"5;
"VSS12"
$PN"32"5;
"VSS11"
$PN"30"5;
"VSS10"
$PN"28"5;
"VSS9"
$PN"26"5;
"VSS8"
$PN"24"5;
"VSS7"
$PN"21"5;
"VSS6"
$PN"19"5;
"VSS5"
$PN"17"5;
"VSS4"
$PN"15"5;
"VSS3"
$PN"13"5;
"VSS2"
$PN"10"5;
"VSS1"
$PN"8"5;
"VSS0"
$PN"6"5;
%"TAP"
"1","(2925,2025)","0","standard","I148";
;
CDS_LIB"standard"
BODY_TYPE"PLUMBING"
HDL_TAP"TRUE";
"B \NAC \NWC"18;
"S \NAC"
BN"0"58;
%"TAP"
"1","(2925,2125)","0","standard","I149";
;
CDS_LIB"standard"
BODY_TYPE"PLUMBING"
HDL_TAP"TRUE";
"B \NAC \NWC"18;
"S \NAC"
BN"1"57;
%"TAP"
"1","(2925,2225)","0","standard","I150";
;
CDS_LIB"standard"
BODY_TYPE"PLUMBING"
HDL_TAP"TRUE";
"B \NAC \NWC"18;
"S \NAC"
BN"2"56;
%"TAP"
"1","(2925,2325)","0","standard","I151";
;
CDS_LIB"standard"
BODY_TYPE"PLUMBING"
HDL_TAP"TRUE";
"B \NAC \NWC"18;
"S \NAC"
BN"3"55;
%"TAP"
"1","(2925,2525)","0","standard","I152";
;
CDS_LIB"standard"
BODY_TYPE"PLUMBING"
HDL_TAP"TRUE";
"B \NAC \NWC"18;
"S \NAC"
BN"5"53;
%"TAP"
"1","(2925,2425)","0","standard","I153";
;
CDS_LIB"standard"
BODY_TYPE"PLUMBING"
HDL_TAP"TRUE";
"B \NAC \NWC"18;
"S \NAC"
BN"4"54;
%"TAP"
"1","(2925,2625)","0","standard","I154";
;
CDS_LIB"standard"
BODY_TYPE"PLUMBING"
HDL_TAP"TRUE";
"B \NAC \NWC"18;
"S \NAC"
BN"6"52;
%"TAP"
"1","(2925,2725)","0","standard","I155";
;
CDS_LIB"standard"
BODY_TYPE"PLUMBING"
HDL_TAP"TRUE";
"B \NAC \NWC"18;
"S \NAC"
BN"7"51;
%"TAP"
"1","(2925,2825)","0","standard","I156";
;
CDS_LIB"standard"
BODY_TYPE"PLUMBING"
HDL_TAP"TRUE";
"B \NAC \NWC"18;
"S \NAC"
BN"8"50;
%"TAP"
"1","(2925,2925)","0","standard","I157";
;
CDS_LIB"standard"
BODY_TYPE"PLUMBING"
HDL_TAP"TRUE";
"B \NAC \NWC"18;
"S \NAC"
BN"9"49;
%"TAP"
"1","(2925,3175)","0","standard","I158";
;
CDS_LIB"standard"
BODY_TYPE"PLUMBING"
HDL_TAP"TRUE";
"B \NAC \NWC"19;
"S \NAC"
BN"1"47;
%"TAP"
"1","(2925,3075)","0","standard","I159";
;
CDS_LIB"standard"
BODY_TYPE"PLUMBING"
HDL_TAP"TRUE";
"B \NAC \NWC"19;
"S \NAC"
BN"0"48;
%"TAP"
"1","(2925,3275)","0","standard","I160";
;
CDS_LIB"standard"
BODY_TYPE"PLUMBING"
HDL_TAP"TRUE";
"B \NAC \NWC"19;
"S \NAC"
BN"2"46;
%"TAP"
"1","(2925,3375)","0","standard","I161";
;
CDS_LIB"standard"
BODY_TYPE"PLUMBING"
HDL_TAP"TRUE";
"B \NAC \NWC"19;
"S \NAC"
BN"3"45;
%"TAP"
"1","(2925,3475)","0","standard","I162";
;
CDS_LIB"standard"
BODY_TYPE"PLUMBING"
HDL_TAP"TRUE";
"B \NAC \NWC"19;
"S \NAC"
BN"4"44;
%"TAP"
"1","(2925,3675)","0","standard","I163";
;
CDS_LIB"standard"
BODY_TYPE"PLUMBING"
HDL_TAP"TRUE";
"B \NAC \NWC"19;
"S \NAC"
BN"6"42;
%"TAP"
"1","(2925,3575)","0","standard","I164";
;
CDS_LIB"standard"
BODY_TYPE"PLUMBING"
HDL_TAP"TRUE";
"B \NAC \NWC"19;
"S \NAC"
BN"5"43;
%"TAP"
"1","(2925,3775)","0","standard","I165";
;
CDS_LIB"standard"
BODY_TYPE"PLUMBING"
HDL_TAP"TRUE";
"B \NAC \NWC"19;
"S \NAC"
BN"7"41;
%"TAP"
"1","(2750,3825)","0","standard","I169";
;
CDS_LIB"standard"
BODY_TYPE"PLUMBING"
HDL_TAP"TRUE";
"B \NAC \NWC"17;
"S \NAC"
BN"7"61;
%"TAP"
"1","(2750,3925)","0","standard","I170";
;
CDS_LIB"standard"
BODY_TYPE"PLUMBING"
HDL_TAP"TRUE";
"B \NAC \NWC"17;
"S \NAC"
BN"8"60;
%"TAP"
"1","(2750,4025)","0","standard","I171";
;
CDS_LIB"standard"
BODY_TYPE"PLUMBING"
HDL_TAP"TRUE";
"B \NAC \NWC"17;
"S \NAC"
BN"9"59;
%"TAP"
"1","(2925,3875)","0","standard","I172";
;
CDS_LIB"standard"
BODY_TYPE"PLUMBING"
HDL_TAP"TRUE";
"B \NAC \NWC"19;
"S \NAC"
BN"8"40;
%"TAP"
"1","(2925,3975)","0","standard","I173";
;
CDS_LIB"standard"
BODY_TYPE"PLUMBING"
HDL_TAP"TRUE";
"B \NAC \NWC"19;
"S \NAC"
BN"9"39;
%"VCC_CORE"
"1","(4425,4575)","0","logical_power","I176";
;
HDL_POWER"P12V_S3_AUX_CPU0_NVDIMM"
CDS_LIB"logical_power";
"A"2;
%"UNIVERSAL_GND"
"1","(6125,325)","0","logical_power","I177";
;
CDS_LIB"logical_power"
HDL_POWER"GND";
"A"5;
%"SCONN288_ADR50017P130CC"
"2","(1850,3025)","0","pure_quanta","I178";
;
PART_NUMBER"DFHST8FS461"
MATERIAL"IO"
PART_TYPE"SMLF"
VALUE"SCONN288_ADR50017-P130CC"
LOCATION"J9"
NEEDS_NO_SIZE"TRUE"
CDS_LMAN_SYM_OUTLINE"-600,1150,600,-1150"
CDS_LIB"pure_quanta"
$SEC"2"
CDS_SEC"2";
"DQS7_A_C||TDQS7_A_C \B"
$PN"178"41;
"DQS6_A_T||TDQS6_A_T"
$PN"168"62;
"DQS8_B_T||TDQS8_B_T"
$PN"283"70;
"DQS8_B_C||TDQS8_B_C \B"
$PN"282"50;
"DQS7_B_T||TDQS7_B_T"
$PN"272"71;
"DQS0_A_C \B"
$PN"12"48;
"DQS0_A_T"
$PN"11"68;
"DQS0_B_C \B"
$PN"105"58;
"DQS0_B_T"
$PN"104"78;
"DQS1_A_C \B"
$PN"23"47;
"DQS1_A_T"
$PN"22"67;
"DQS1_B_C \B"
$PN"116"57;
"DQS1_B_T"
$PN"115"77;
"DQS2_A_C \B"
$PN"34"46;
"DQS2_A_T"
$PN"33"66;
"DQS2_B_C \B"
$PN"127"56;
"DQS2_B_T"
$PN"126"76;
"DQS3_A_C \B"
$PN"45"45;
"DQS3_A_T"
$PN"44"65;
"DQS3_B_C \B"
$PN"138"55;
"DQS3_B_T"
$PN"137"75;
"DQS4_A_C \B"
$PN"56"44;
"DQS4_A_T"
$PN"55"64;
"DQS4_B_C \B"
$PN"238"54;
"DQS4_B_T"
$PN"239"74;
"DQS5_A_C||TDQS5_A_C||DQS5_A_T||TDQS5_A_T \B"
$PN"156"43;
"DQS5_A_T||TDQS5_A_T"
$PN"157"63;
"DQS5_B_C||TDQS5_B_C \B"
$PN"249"53;
"DQS5_B_T||TDQS5_B_T"
$PN"250"73;
"DQS6_A_C||TDQS6_A_C||DQS6_A_T||TDQS6_A_T \B"
$PN"167"42;
"DQS6_B_C||TDQS6_B_C \B"
$PN"260"52;
"DQS6_B_T||TDQS6_B_T"
$PN"261"72;
"DQS7_A_T||TDQS7_A_T"
$PN"179"61;
"DQS7_B_C||TDQS7_B_C \B"
$PN"271"51;
"DQS8_A_C||TDQS8_A_C \B"
$PN"189"40;
"DQS8_A_T||TDQS8_A_T"
$PN"190"60;
"DQS9_A_C||TDQS9_A_C \B"
$PN"200"39;
"DQS9_A_T||TDQS9_A_T"
$PN"201"59;
"DQS9_B_C||TDQS9_B_C \B"
$PN"94"49;
"DQS9_B_T||TDQS9_B_T||DBI4_B_N"
$PN"93"69;
%"Q_RES"
"1","(-2650,1325)","0","pure_quanta","I179";
;
PART_NUMBER"CS04992FB07"
MATERIAL"CHIP"
VALUE"49.9"
$LOCATION"R3883"
CDS_LIB"pure_quanta"
PACK_TYPE"0402LF"
TOLERANCE"1%"
WATTAGE"1/16W"
CDS_LOCATION"R3883"
$SEC"1"
CDS_SEC"1";
"B"
$PN"2"26;
"A"
$PN"1"27;
%"TAP"
"1","(-1650,1875)","2","standard","I25";
;
CDS_LIB"standard"
BODY_TYPE"PLUMBING"
HDL_TAP"TRUE";
"B \NAC \NWC"12;
"S \NAC"
BN"1"153;
%"TAP"
"1","(-1650,1825)","2","standard","I26";
;
CDS_LIB"standard"
BODY_TYPE"PLUMBING"
HDL_TAP"TRUE";
"B \NAC \NWC"12;
"S \NAC"
BN"0"152;
%"TAP"
"1","(-1650,1925)","2","standard","I27";
;
CDS_LIB"standard"
BODY_TYPE"PLUMBING"
HDL_TAP"TRUE";
"B \NAC \NWC"12;
"S \NAC"
BN"2"154;
%"TAP"
"1","(-1650,1975)","2","standard","I28";
;
CDS_LIB"standard"
BODY_TYPE"PLUMBING"
HDL_TAP"TRUE";
"B \NAC \NWC"12;
"S \NAC"
BN"3"155;
%"TAP"
"1","(-1650,2025)","2","standard","I29";
;
CDS_LIB"standard"
BODY_TYPE"PLUMBING"
HDL_TAP"TRUE";
"B \NAC \NWC"12;
"S \NAC"
BN"4"156;
%"TAP"
"1","(-1650,2125)","2","standard","I30";
;
CDS_LIB"standard"
BODY_TYPE"PLUMBING"
HDL_TAP"TRUE";
"B \NAC \NWC"12;
"S \NAC"
BN"6"94;
%"TAP"
"1","(-1650,2075)","2","standard","I31";
;
CDS_LIB"standard"
BODY_TYPE"PLUMBING"
HDL_TAP"TRUE";
"B \NAC \NWC"12;
"S \NAC"
BN"5"95;
%"TAP"
"1","(-1650,2175)","2","standard","I32";
;
CDS_LIB"standard"
BODY_TYPE"PLUMBING"
HDL_TAP"TRUE";
"B \NAC \NWC"12;
"S \NAC"
BN"7"173;
%"TAP"
"1","(-1650,2275)","2","standard","I33";
;
CDS_LIB"standard"
BODY_TYPE"PLUMBING"
HDL_TAP"TRUE";
"B \NAC \NWC"11;
"S \NAC"
BN"0"93;
%"TAP"
"1","(-1650,2325)","2","standard","I34";
;
CDS_LIB"standard"
BODY_TYPE"PLUMBING"
HDL_TAP"TRUE";
"B \NAC \NWC"11;
"S \NAC"
BN"1"174;
%"TAP"
"1","(-1650,2375)","2","standard","I35";
;
CDS_LIB"standard"
BODY_TYPE"PLUMBING"
HDL_TAP"TRUE";
"B \NAC \NWC"11;
"S \NAC"
BN"2"157;
%"TAP"
"1","(-1650,2425)","2","standard","I36";
;
CDS_LIB"standard"
BODY_TYPE"PLUMBING"
HDL_TAP"TRUE";
"B \NAC \NWC"11;
"S \NAC"
BN"3"158;
%"TAP"
"1","(-1650,2475)","2","standard","I37";
;
CDS_LIB"standard"
BODY_TYPE"PLUMBING"
HDL_TAP"TRUE";
"B \NAC \NWC"11;
"S \NAC"
BN"4"175;
%"TAP"
"1","(-1650,2525)","2","standard","I38";
;
CDS_LIB"standard"
BODY_TYPE"PLUMBING"
HDL_TAP"TRUE";
"B \NAC \NWC"11;
"S \NAC"
BN"5"159;
%"TAP"
"1","(-1650,2625)","2","standard","I39";
;
CDS_LIB"standard"
BODY_TYPE"PLUMBING"
HDL_TAP"TRUE";
"B \NAC \NWC"11;
"S \NAC"
BN"7"176;
%"TAP"
"1","(-1650,2575)","2","standard","I40";
;
CDS_LIB"standard"
BODY_TYPE"PLUMBING"
HDL_TAP"TRUE";
"B \NAC \NWC"11;
"S \NAC"
BN"6"160;
%"TAP"
"1","(-1650,3325)","2","standard","I41";
;
CDS_LIB"standard"
BODY_TYPE"PLUMBING"
HDL_TAP"TRUE";
"B \NAC \NWC"14;
"S \NAC"
BN"0"171;
%"TAP"
"1","(-1650,3375)","2","standard","I42";
;
CDS_LIB"standard"
BODY_TYPE"PLUMBING"
HDL_TAP"TRUE";
"B \NAC \NWC"14;
"S \NAC"
BN"1"81;
%"TAP"
"1","(-1650,3425)","2","standard","I43";
;
CDS_LIB"standard"
BODY_TYPE"PLUMBING"
HDL_TAP"TRUE";
"B \NAC \NWC"14;
"S \NAC"
BN"2"80;
%"TAP"
"1","(-1650,3525)","2","standard","I44";
;
CDS_LIB"standard"
BODY_TYPE"PLUMBING"
HDL_TAP"TRUE";
"B \NAC \NWC"14;
"S \NAC"
BN"4"165;
%"TAP"
"1","(-1650,3475)","2","standard","I45";
;
CDS_LIB"standard"
BODY_TYPE"PLUMBING"
HDL_TAP"TRUE";
"B \NAC \NWC"14;
"S \NAC"
BN"3"167;
%"TAP"
"1","(-1650,3625)","2","standard","I46";
;
CDS_LIB"standard"
BODY_TYPE"PLUMBING"
HDL_TAP"TRUE";
"B \NAC \NWC"14;
"S \NAC"
BN"6"161;
%"TAP"
"1","(-1650,3575)","2","standard","I47";
;
CDS_LIB"standard"
BODY_TYPE"PLUMBING"
HDL_TAP"TRUE";
"B \NAC \NWC"14;
"S \NAC"
BN"5"163;
%"TAP"
"1","(-1650,3775)","2","standard","I48";
;
CDS_LIB"standard"
BODY_TYPE"PLUMBING"
HDL_TAP"TRUE";
"B \NAC \NWC"13;
"S \NAC"
BN"1"170;
%"TAP"
"1","(-1650,3725)","2","standard","I49";
;
CDS_LIB"standard"
BODY_TYPE"PLUMBING"
HDL_TAP"TRUE";
"B \NAC \NWC"13;
"S \NAC"
BN"0"172;
%"TAP"
"1","(0,825)","0","standard","I50";
;
CDS_LIB"standard"
BODY_TYPE"PLUMBING"
HDL_TAP"TRUE";
"B \NAC \NWC"15;
"S \NAC"
BN"0"101;
%"TAP"
"1","(0,875)","0","standard","I51";
;
CDS_LIB"standard"
BODY_TYPE"PLUMBING"
HDL_TAP"TRUE";
"B \NAC \NWC"15;
"S \NAC"
BN"1"102;
%"TAP"
"1","(0,975)","0","standard","I52";
;
CDS_LIB"standard"
BODY_TYPE"PLUMBING"
HDL_TAP"TRUE";
"B \NAC \NWC"15;
"S \NAC"
BN"3"104;
%"TAP"
"1","(0,925)","0","standard","I53";
;
CDS_LIB"standard"
BODY_TYPE"PLUMBING"
HDL_TAP"TRUE";
"B \NAC \NWC"15;
"S \NAC"
BN"2"103;
%"TAP"
"1","(0,1125)","0","standard","I54";
;
CDS_LIB"standard"
BODY_TYPE"PLUMBING"
HDL_TAP"TRUE";
"B \NAC \NWC"15;
"S \NAC"
BN"6"107;
%"TAP"
"1","(0,1075)","0","standard","I55";
;
CDS_LIB"standard"
BODY_TYPE"PLUMBING"
HDL_TAP"TRUE";
"B \NAC \NWC"15;
"S \NAC"
BN"5"106;
%"TAP"
"1","(0,1025)","0","standard","I56";
;
CDS_LIB"standard"
BODY_TYPE"PLUMBING"
HDL_TAP"TRUE";
"B \NAC \NWC"15;
"S \NAC"
BN"4"105;
%"TAP"
"1","(0,1175)","0","standard","I57";
;
CDS_LIB"standard"
BODY_TYPE"PLUMBING"
HDL_TAP"TRUE";
"B \NAC \NWC"15;
"S \NAC"
BN"7"108;
%"TAP"
"1","(0,1225)","0","standard","I58";
;
CDS_LIB"standard"
BODY_TYPE"PLUMBING"
HDL_TAP"TRUE";
"B \NAC \NWC"15;
"S \NAC"
BN"8"109;
%"TAP"
"1","(0,1275)","0","standard","I59";
;
CDS_LIB"standard"
BODY_TYPE"PLUMBING"
HDL_TAP"TRUE";
"B \NAC \NWC"15;
"S \NAC"
BN"9"110;
%"TAP"
"1","(0,1325)","0","standard","I60";
;
CDS_LIB"standard"
BODY_TYPE"PLUMBING"
HDL_TAP"TRUE";
"B \NAC \NWC"15;
"S \NAC"
BN"10"111;
%"TAP"
"1","(0,1375)","0","standard","I61";
;
CDS_LIB"standard"
BODY_TYPE"PLUMBING"
HDL_TAP"TRUE";
"B \NAC \NWC"15;
"S \NAC"
BN"11"112;
%"TAP"
"1","(0,1425)","0","standard","I62";
;
CDS_LIB"standard"
BODY_TYPE"PLUMBING"
HDL_TAP"TRUE";
"B \NAC \NWC"15;
"S \NAC"
BN"12"113;
%"TAP"
"1","(0,1475)","0","standard","I63";
;
CDS_LIB"standard"
BODY_TYPE"PLUMBING"
HDL_TAP"TRUE";
"B \NAC \NWC"15;
"S \NAC"
BN"13"114;
%"TAP"
"1","(0,1525)","0","standard","I64";
;
CDS_LIB"standard"
BODY_TYPE"PLUMBING"
HDL_TAP"TRUE";
"B \NAC \NWC"15;
"S \NAC"
BN"14"115;
%"TAP"
"1","(0,1575)","0","standard","I65";
;
CDS_LIB"standard"
BODY_TYPE"PLUMBING"
HDL_TAP"TRUE";
"B \NAC \NWC"15;
"S \NAC"
BN"15"97;
%"TAP"
"1","(0,1625)","0","standard","I66";
;
CDS_LIB"standard"
BODY_TYPE"PLUMBING"
HDL_TAP"TRUE";
"B \NAC \NWC"15;
"S \NAC"
BN"16"116;
%"TAP"
"1","(0,1675)","0","standard","I67";
;
CDS_LIB"standard"
BODY_TYPE"PLUMBING"
HDL_TAP"TRUE";
"B \NAC \NWC"15;
"S \NAC"
BN"17"117;
%"TAP"
"1","(0,1725)","0","standard","I68";
;
CDS_LIB"standard"
BODY_TYPE"PLUMBING"
HDL_TAP"TRUE";
"B \NAC \NWC"15;
"S \NAC"
BN"18"118;
%"TAP"
"1","(0,1775)","0","standard","I69";
;
CDS_LIB"standard"
BODY_TYPE"PLUMBING"
HDL_TAP"TRUE";
"B \NAC \NWC"15;
"S \NAC"
BN"19"119;
%"TAP"
"1","(0,1875)","0","standard","I70";
;
CDS_LIB"standard"
BODY_TYPE"PLUMBING"
HDL_TAP"TRUE";
"B \NAC \NWC"15;
"S \NAC"
BN"21"120;
%"TAP"
"1","(0,1825)","0","standard","I71";
;
CDS_LIB"standard"
BODY_TYPE"PLUMBING"
HDL_TAP"TRUE";
"B \NAC \NWC"15;
"S \NAC"
BN"20"96;
%"TAP"
"1","(0,1975)","0","standard","I72";
;
CDS_LIB"standard"
BODY_TYPE"PLUMBING"
HDL_TAP"TRUE";
"B \NAC \NWC"15;
"S \NAC"
BN"23"122;
%"TAP"
"1","(0,2025)","0","standard","I73";
;
CDS_LIB"standard"
BODY_TYPE"PLUMBING"
HDL_TAP"TRUE";
"B \NAC \NWC"15;
"S \NAC"
BN"24"123;
%"TAP"
"1","(0,1925)","0","standard","I74";
;
CDS_LIB"standard"
BODY_TYPE"PLUMBING"
HDL_TAP"TRUE";
"B \NAC \NWC"15;
"S \NAC"
BN"22"121;
%"TAP"
"1","(0,2075)","0","standard","I75";
;
CDS_LIB"standard"
BODY_TYPE"PLUMBING"
HDL_TAP"TRUE";
"B \NAC \NWC"15;
"S \NAC"
BN"25"124;
%"TAP"
"1","(0,2125)","0","standard","I76";
;
CDS_LIB"standard"
BODY_TYPE"PLUMBING"
HDL_TAP"TRUE";
"B \NAC \NWC"15;
"S \NAC"
BN"26"125;
%"TAP"
"1","(0,2175)","0","standard","I77";
;
CDS_LIB"standard"
BODY_TYPE"PLUMBING"
HDL_TAP"TRUE";
"B \NAC \NWC"15;
"S \NAC"
BN"27"126;
%"TAP"
"1","(0,2225)","0","standard","I78";
;
CDS_LIB"standard"
BODY_TYPE"PLUMBING"
HDL_TAP"TRUE";
"B \NAC \NWC"15;
"S \NAC"
BN"28"92;
%"TAP"
"1","(0,2275)","0","standard","I79";
;
CDS_LIB"standard"
BODY_TYPE"PLUMBING"
HDL_TAP"TRUE";
"B \NAC \NWC"15;
"S \NAC"
BN"29"38;
%"TAP"
"1","(0,2375)","0","standard","I80";
;
CDS_LIB"standard"
BODY_TYPE"PLUMBING"
HDL_TAP"TRUE";
"B \NAC \NWC"15;
"S \NAC"
BN"31"127;
%"TAP"
"1","(0,2325)","0","standard","I81";
;
CDS_LIB"standard"
BODY_TYPE"PLUMBING"
HDL_TAP"TRUE";
"B \NAC \NWC"15;
"S \NAC"
BN"30"91;
%"TAP"
"1","(0,2475)","0","standard","I82";
;
CDS_LIB"standard"
BODY_TYPE"PLUMBING"
HDL_TAP"TRUE";
"B \NAC \NWC"10;
"S \NAC"
BN"0"128;
%"TAP"
"1","(0,2525)","0","standard","I83";
;
CDS_LIB"standard"
BODY_TYPE"PLUMBING"
HDL_TAP"TRUE";
"B \NAC \NWC"10;
"S \NAC"
BN"1"129;
%"TAP"
"1","(0,2575)","0","standard","I84";
;
CDS_LIB"standard"
BODY_TYPE"PLUMBING"
HDL_TAP"TRUE";
"B \NAC \NWC"10;
"S \NAC"
BN"2"130;
%"TAP"
"1","(0,2625)","0","standard","I85";
;
CDS_LIB"standard"
BODY_TYPE"PLUMBING"
HDL_TAP"TRUE";
"B \NAC \NWC"10;
"S \NAC"
BN"3"131;
%"TAP"
"1","(0,2675)","0","standard","I86";
;
CDS_LIB"standard"
BODY_TYPE"PLUMBING"
HDL_TAP"TRUE";
"B \NAC \NWC"10;
"S \NAC"
BN"4"86;
%"TAP"
"1","(0,2725)","0","standard","I87";
;
CDS_LIB"standard"
BODY_TYPE"PLUMBING"
HDL_TAP"TRUE";
"B \NAC \NWC"10;
"S \NAC"
BN"5"87;
%"TAP"
"1","(0,2775)","0","standard","I88";
;
CDS_LIB"standard"
BODY_TYPE"PLUMBING"
HDL_TAP"TRUE";
"B \NAC \NWC"10;
"S \NAC"
BN"6"90;
%"TAP"
"1","(0,2875)","0","standard","I89";
;
CDS_LIB"standard"
BODY_TYPE"PLUMBING"
HDL_TAP"TRUE";
"B \NAC \NWC"10;
"S \NAC"
BN"8"89;
%"TAP"
"1","(0,2825)","0","standard","I90";
;
CDS_LIB"standard"
BODY_TYPE"PLUMBING"
HDL_TAP"TRUE";
"B \NAC \NWC"10;
"S \NAC"
BN"7"132;
%"TAP"
"1","(0,2925)","0","standard","I91";
;
CDS_LIB"standard"
BODY_TYPE"PLUMBING"
HDL_TAP"TRUE";
"B \NAC \NWC"10;
"S \NAC"
BN"9"88;
%"TAP"
"1","(0,3025)","0","standard","I92";
;
CDS_LIB"standard"
BODY_TYPE"PLUMBING"
HDL_TAP"TRUE";
"B \NAC \NWC"10;
"S \NAC"
BN"11"133;
%"TAP"
"1","(0,2975)","0","standard","I93";
;
CDS_LIB"standard"
BODY_TYPE"PLUMBING"
HDL_TAP"TRUE";
"B \NAC \NWC"10;
"S \NAC"
BN"10"85;
%"TAP"
"1","(0,3125)","0","standard","I94";
;
CDS_LIB"standard"
BODY_TYPE"PLUMBING"
HDL_TAP"TRUE";
"B \NAC \NWC"10;
"S \NAC"
BN"13"135;
%"TAP"
"1","(0,3175)","0","standard","I95";
;
CDS_LIB"standard"
BODY_TYPE"PLUMBING"
HDL_TAP"TRUE";
"B \NAC \NWC"10;
"S \NAC"
BN"14"136;
%"TAP"
"1","(0,3075)","0","standard","I96";
;
CDS_LIB"standard"
BODY_TYPE"PLUMBING"
HDL_TAP"TRUE";
"B \NAC \NWC"10;
"S \NAC"
BN"12"134;
%"TAP"
"1","(0,3275)","0","standard","I97";
;
CDS_LIB"standard"
BODY_TYPE"PLUMBING"
HDL_TAP"TRUE";
"B \NAC \NWC"10;
"S \NAC"
BN"16"138;
%"TAP"
"1","(0,3225)","0","standard","I98";
;
CDS_LIB"standard"
BODY_TYPE"PLUMBING"
HDL_TAP"TRUE";
"B \NAC \NWC"10;
"S \NAC"
BN"15"137;
%"TAP"
"1","(0,3425)","0","standard","I99";
;
CDS_LIB"standard"
BODY_TYPE"PLUMBING"
HDL_TAP"TRUE";
"B \NAC \NWC"10;
"S \NAC"
BN"19"141;
END.
